# SCM (Grand Teton) — schematic netlist excerpt (pin names and nets, part order shuffled) for the footprints in the layout excerpt that follows; sources: Cadence DE-HDL packaged netlist, KiCad conversion of 12092022_DA0F0TMDCD0_F0T_Management_Board_D_brd_V3_OCP.brd

R366  Q_RES  120 1% CHIP  pkg 0402LF  page 20 : A = M_BMC_DDR4_MCAS_N ; B = P1V2_AUX
R206  Q_RES  10K 1% CHIP  pkg 0402LF  page 32 : A = GND ; B = JTAG_SCM_NTRST

(kicad_pcb
	(version 20260206)
	(generator "pcbnew")
	(generator_version "10.0")
	(general
		(thickness 1.6)
		(legacy_teardrops no)
	)
	(paper "A4")
	(title_block
		(title "12092022_DA0F0TMDCD0_F0T_Management_Board_D_brd_V3_OCP.brd")
		(comment 1 "Grand Teton / footprints 761-762 of 1440")
	)
	(layers
		(0 "F.Cu" signal "TOP")
		(4 "In1.Cu" signal "GND")
		(6 "In2.Cu" signal "IN1")
		(8 "In3.Cu" signal "GND1")
		(10 "In4.Cu" signal "IN2")
		(12 "In5.Cu" signal "VCC")
		(14 "In6.Cu" signal "VCC1")
		(16 "In7.Cu" signal "IN3")
		(18 "In8.Cu" signal "GND2")
		(20 "In9.Cu" signal "IN4")
		(22 "In10.Cu" signal "GND3")
		(2 "B.Cu" signal "BOTTOM")
		(9 "F.Adhes" user "F.Adhesive")
		(11 "B.Adhes" user "B.Adhesive")
		(13 "F.Paste" user "Package Geometry/Pastemask Top")
		(15 "B.Paste" user "Package Geometry/Pastemask Bottom")
		(5 "F.SilkS" user "Ref Des/Silkscreen Top")
		(7 "B.SilkS" user "Ref Des/Silkscreen Bottom")
		(1 "F.Mask" user "Board Geometry/Soldermask Top")
		(3 "B.Mask" user "Board Geometry/Soldermask Bottom")
		(17 "Dwgs.User" user "User.Drawings")
		(19 "Cmts.User" user "User.Comments")
		(21 "Eco1.User" user "User.Eco1")
		(23 "Eco2.User" user "User.Eco2")
		(25 "Edge.Cuts" user "Board Geometry/Outline")
		(27 "Margin" user)
		(31 "F.CrtYd" user "Package Geometry/Place Bound Top")
		(29 "B.CrtYd" user "Package Geometry/Place Bound Bottom")
		(35 "F.Fab" user "Ref Des/Assembly Top")
		(33 "B.Fab" user "Ref Des/Assembly Bottom")
	)
	(footprint ""
		(layer "B.Cu")
		(at 85.29955 -48.504094 180)
		(property "Reference" "R366"
			(at 0 0 0)
			(layer "B.SilkS")
			(hide yes)
			(effects
				(font
					(size 1.27 1.27)
				)
				(justify mirror)
			)
		)
		(property "Value" ""
			(at 0 0 0)
			(layer "B.Fab")
			(effects
				(font
					(size 1.27 1.27)
				)
				(justify mirror)
			)
		)
		(duplicate_pad_numbers_are_jumpers no)
		(fp_line
			(start 0.7874 0.4064)
			(end 0.7874 -0.4064)
			(stroke
				(width 0.1524)
				(type default)
			)
			(layer "B.SilkS")
		)
		(fp_line
			(start 0.7874 -0.4064)
			(end -0.7874 -0.4064)
			(stroke
				(width 0.1524)
				(type default)
			)
			(layer "B.SilkS")
		)
		(fp_line
			(start -0.7874 0.4064)
			(end 0.7874 0.4064)
			(stroke
				(width 0.1524)
				(type default)
			)
			(layer "B.SilkS")
		)
		(fp_line
			(start -0.7874 -0.4064)
			(end -0.7874 0.4064)
			(stroke
				(width 0.1524)
				(type default)
			)
			(layer "B.SilkS")
		)
		(fp_line
			(start 0.67945 0.3048)
			(end 0.67945 -0.305054)
			(stroke
				(width 0.1)
				(type default)
			)
			(layer "B.Fab")
		)
		(fp_line
			(start 0.67945 -0.305054)
			(end 0.12065 -0.305054)
			(stroke
				(width 0.1)
				(type default)
			)
			(layer "B.Fab")
		)
		(fp_line
			(start 0.12065 0.3048)
			(end 0.67945 0.3048)
			(stroke
				(width 0.1)
				(type default)
			)
			(layer "B.Fab")
		)
		(fp_line
			(start 0.12065 0.2794)
			(end 0.12065 0.3048)
			(stroke
				(width 0.1)
				(type default)
			)
			(layer "B.Fab")
		)
		(fp_line
			(start 0.12065 -0.2794)
			(end -0.12065 -0.2794)
			(stroke
				(width 0.1)
				(type default)
			)
			(layer "B.Fab")
		)
		(fp_line
			(start 0.12065 -0.305054)
			(end 0.12065 -0.2794)
			(stroke
				(width 0.1)
				(type default)
			)
			(layer "B.Fab")
		)
		(fp_line
			(start -0.120396 0.3048)
			(end -0.120396 0.2794)
			(stroke
				(width 0.1)
				(type default)
			)
			(layer "B.Fab")
		)
		(fp_line
			(start -0.120396 0.2794)
			(end 0.12065 0.2794)
			(stroke
				(width 0.1)
				(type default)
			)
			(layer "B.Fab")
		)
		(fp_line
			(start -0.12065 -0.2794)
			(end -0.12065 -0.3048)
			(stroke
				(width 0.1)
				(type default)
			)
			(layer "B.Fab")
		)
		(fp_line
			(start -0.12065 -0.3048)
			(end -0.67945 -0.3048)
			(stroke
				(width 0.1)
				(type default)
			)
			(layer "B.Fab")
		)
		(fp_line
			(start -0.67945 0.3048)
			(end -0.120396 0.3048)
			(stroke
				(width 0.1)
				(type default)
			)
			(layer "B.Fab")
		)
		(fp_line
			(start -0.67945 -0.3048)
			(end -0.67945 0.3048)
			(stroke
				(width 0.1)
				(type default)
			)
			(layer "B.Fab")
		)
		(pad "1" smd circle
			(at 0.40005 0)
			(size 0 0)
			(layers "B.Cu" "B.Mask" "B.Paste")
			(net "M_BMC_DDR4_MCAS_N")
		)
		(pad "2" smd circle
			(at -0.40005 0)
			(size 0 0)
			(layers "B.Cu" "B.Mask" "B.Paste")
			(net "P1V2_AUX")
		)
	)
	(footprint ""
		(layer "B.Cu")
		(at 66.513202 -37.038788 90)
		(property "Reference" "R206"
			(at 0 0 90)
			(layer "B.SilkS")
			(hide yes)
			(effects
				(font
					(size 1.27 1.27)
				)
				(justify mirror)
			)
		)
		(property "Value" ""
			(at 0 0 90)
			(layer "B.Fab")
			(effects
				(font
					(size 1.27 1.27)
				)
				(justify mirror)
			)
		)
		(duplicate_pad_numbers_are_jumpers no)
		(fp_line
			(start 0.7874 -0.4064)
			(end -0.7874 -0.4064)
			(stroke
				(width 0.1524)
				(type default)
			)
			(layer "B.SilkS")
		)
		(fp_line
			(start -0.7874 -0.4064)
			(end -0.7874 0.4064)
			(stroke
				(width 0.1524)
				(type default)
			)
			(layer "B.SilkS")
		)
		(fp_line
			(start 0.7874 0.4064)
			(end 0.7874 -0.4064)
			(stroke
				(width 0.1524)
				(type default)
			)
			(layer "B.SilkS")
		)
		(fp_line
			(start -0.7874 0.4064)
			(end 0.7874 0.4064)
			(stroke
				(width 0.1524)
				(type default)
			)
			(layer "B.SilkS")
		)
		(fp_line
			(start 0.67945 -0.305054)
			(end 0.12065 -0.305054)
			(stroke
				(width 0.1)
				(type default)
			)
			(layer "B.Fab")
		)
		(fp_line
			(start 0.12065 -0.305054)
			(end 0.12065 -0.2794)
			(stroke
				(width 0.1)
				(type default)
			)
			(layer "B.Fab")
		)
		(fp_line
			(start -0.12065 -0.3048)
			(end -0.67945 -0.3048)
			(stroke
				(width 0.1)
				(type default)
			)
			(layer "B.Fab")
		)
		(fp_line
			(start -0.67945 -0.3048)
			(end -0.67945 0.3048)
			(stroke
				(width 0.1)
				(type default)
			)
			(layer "B.Fab")
		)
		(fp_line
			(start 0.12065 -0.2794)
			(end -0.12065 -0.2794)
			(stroke
				(width 0.1)
				(type default)
			)
			(layer "B.Fab")
		)
		(fp_line
			(start -0.12065 -0.2794)
			(end -0.12065 -0.3048)
			(stroke
				(width 0.1)
				(type default)
			)
			(layer "B.Fab")
		)
		(fp_line
			(start 0.12065 0.2794)
			(end 0.12065 0.3048)
			(stroke
				(width 0.1)
				(type default)
			)
			(layer "B.Fab")
		)
		(fp_line
			(start -0.120396 0.2794)
			(end 0.12065 0.2794)
			(stroke
				(width 0.1)
				(type default)
			)
			(layer "B.Fab")
		)
		(fp_line
			(start 0.67945 0.3048)
			(end 0.67945 -0.305054)
			(stroke
				(width 0.1)
				(type default)
			)
			(layer "B.Fab")
		)
		(fp_line
			(start 0.12065 0.3048)
			(end 0.67945 0.3048)
			(stroke
				(width 0.1)
				(type default)
			)
			(layer "B.Fab")
		)
		(fp_line
			(start -0.120396 0.3048)
			(end -0.120396 0.2794)
			(stroke
				(width 0.1)
				(type default)
			)
			(layer "B.Fab")
		)
		(fp_line
			(start -0.67945 0.3048)
			(end -0.120396 0.3048)
			(stroke
				(width 0.1)
				(type default)
			)
			(layer "B.Fab")
		)
		(pad "1" smd circle
			(at 0.40005 0 270)
			(size 0 0)
			(layers "B.Cu" "B.Mask" "B.Paste")
			(net "GND")
		)
		(pad "2" smd circle
			(at -0.40005 0 270)
			(size 0 0)
			(layers "B.Cu" "B.Mask" "B.Paste")
			(net "JTAG_SCM_NTRST")
		)
	)
)
